# S9S_MB_2U (Grand Teton) — schematic netlist excerpt (pin names and nets, part order shuffled) for the footprints in the layout excerpt that follows; sources: Cadence DE-HDL packaged netlist, KiCad conversion of 03242023_DA0F0TMBIJ0_F0T_Motherboard_J_brd_V01_OCP.brd

H27  HOLE  EMPTY  pkg TH  page 311 : \1\ = NC
R1149  Q_RES  10K 1% CHIP  pkg 0402LF  page 156 : A = P3V3_AUX ; B = HP_LVC3_OCP_V3_1_ATTN_OUT_SW_N
R3508  Q_RES  54.9K 1% CHIP  pkg 0402LF  page 151 : A = FM_GPU_PWR_EN_R1 ; B = GND

(kicad_pcb
	(version 20260206)
	(generator "pcbnew")
	(generator_version "10.0")
	(general
		(thickness 1.6)
		(legacy_teardrops no)
	)
	(paper "A4")
	(title_block
		(title "03242023_DA0F0TMBIJ0_F0T_Motherboard_J_brd_V01_OCP.brd")
		(comment 1 "Grand Teton / footprints 891-893 of 6105")
	)
	(layers
		(0 "F.Cu" signal "TOP")
		(4 "In1.Cu" signal "GND")
		(6 "In2.Cu" signal "IN1")
		(8 "In3.Cu" signal "GND1")
		(10 "In4.Cu" signal "IN2")
		(12 "In5.Cu" signal "GND2")
		(14 "In6.Cu" signal "IN3")
		(16 "In7.Cu" signal "GND3")
		(18 "In8.Cu" signal "VCC")
		(20 "In9.Cu" signal "VCC1")
		(22 "In10.Cu" signal "GND4")
		(24 "In11.Cu" signal "IN4")
		(26 "In12.Cu" signal "GND5")
		(28 "In13.Cu" signal "IN5")
		(30 "In14.Cu" signal "GND6")
		(32 "In15.Cu" signal "IN6")
		(34 "In16.Cu" signal "GND7")
		(2 "B.Cu" signal "BOTTOM")
		(9 "F.Adhes" user "F.Adhesive")
		(11 "B.Adhes" user "B.Adhesive")
		(13 "F.Paste" user "Package Geometry/Pastemask Top")
		(15 "B.Paste" user "Package Geometry/Pastemask Bottom")
		(5 "F.SilkS" user "Ref Des/Silkscreen Top")
		(7 "B.SilkS" user "Ref Des/Silkscreen Bottom")
		(1 "F.Mask" user "Board Geometry/Soldermask Top")
		(3 "B.Mask" user "Board Geometry/Soldermask Bottom")
		(17 "Dwgs.User" user "User.Drawings")
		(19 "Cmts.User" user "User.Comments")
		(21 "Eco1.User" user "User.Eco1")
		(23 "Eco2.User" user "User.Eco2")
		(25 "Edge.Cuts" user "Board Geometry/Outline")
		(27 "Margin" user)
		(31 "F.CrtYd" user "Package Geometry/Place Bound Top")
		(29 "B.CrtYd" user "Package Geometry/Place Bound Bottom")
		(35 "F.Fab" user "Ref Des/Assembly Top")
		(33 "B.Fab" user "Ref Des/Assembly Bottom")
	)
	(footprint ""
		(layer "F.Cu")
		(at 465.043266 -101.39299 180)
		(property "Reference" "R1149"
			(at 0 0 180)
			(layer "F.SilkS")
			(hide yes)
			(effects
				(font
					(size 1.27 1.27)
				)
			)
		)
		(property "Value" ""
			(at 0 0 180)
			(layer "F.Fab")
			(effects
				(font
					(size 1.27 1.27)
				)
			)
		)
		(duplicate_pad_numbers_are_jumpers no)
		(fp_line
			(start 0.7874 0.4064)
			(end -0.7874 0.4064)
			(stroke
				(width 0.1524)
				(type default)
			)
			(layer "F.SilkS")
		)
		(fp_line
			(start 0.7874 -0.4064)
			(end 0.7874 0.4064)
			(stroke
				(width 0.1524)
				(type default)
			)
			(layer "F.SilkS")
		)
		(fp_line
			(start -0.7874 0.4064)
			(end -0.7874 -0.4064)
			(stroke
				(width 0.1524)
				(type default)
			)
			(layer "F.SilkS")
		)
		(fp_line
			(start -0.7874 -0.4064)
			(end 0.7874 -0.4064)
			(stroke
				(width 0.1524)
				(type default)
			)
			(layer "F.SilkS")
		)
		(fp_line
			(start 0.67945 0.3048)
			(end 0.120396 0.3048)
			(stroke
				(width 0.1)
				(type default)
			)
			(layer "F.Fab")
		)
		(fp_line
			(start 0.67945 -0.3048)
			(end 0.67945 0.3048)
			(stroke
				(width 0.1)
				(type default)
			)
			(layer "F.Fab")
		)
		(fp_line
			(start 0.12065 -0.2794)
			(end 0.12065 -0.3048)
			(stroke
				(width 0.1)
				(type default)
			)
			(layer "F.Fab")
		)
		(fp_line
			(start 0.12065 -0.3048)
			(end 0.67945 -0.3048)
			(stroke
				(width 0.1)
				(type default)
			)
			(layer "F.Fab")
		)
		(fp_line
			(start 0.120396 0.3048)
			(end 0.120396 0.2794)
			(stroke
				(width 0.1)
				(type default)
			)
			(layer "F.Fab")
		)
		(fp_line
			(start 0.120396 0.2794)
			(end -0.12065 0.2794)
			(stroke
				(width 0.1)
				(type default)
			)
			(layer "F.Fab")
		)
		(fp_line
			(start -0.12065 0.3048)
			(end -0.67945 0.3048)
			(stroke
				(width 0.1)
				(type default)
			)
			(layer "F.Fab")
		)
		(fp_line
			(start -0.12065 0.2794)
			(end -0.12065 0.3048)
			(stroke
				(width 0.1)
				(type default)
			)
			(layer "F.Fab")
		)
		(fp_line
			(start -0.12065 -0.2794)
			(end 0.12065 -0.2794)
			(stroke
				(width 0.1)
				(type default)
			)
			(layer "F.Fab")
		)
		(fp_line
			(start -0.12065 -0.305054)
			(end -0.12065 -0.2794)
			(stroke
				(width 0.1)
				(type default)
			)
			(layer "F.Fab")
		)
		(fp_line
			(start -0.67945 0.3048)
			(end -0.67945 -0.305054)
			(stroke
				(width 0.1)
				(type default)
			)
			(layer "F.Fab")
		)
		(fp_line
			(start -0.67945 -0.305054)
			(end -0.12065 -0.305054)
			(stroke
				(width 0.1)
				(type default)
			)
			(layer "F.Fab")
		)
		(pad "1" smd circle
			(at -0.40005 0 180)
			(size 0 0)
			(layers "F.Cu" "F.Mask" "F.Paste")
			(net "P3V3_AUX")
		)
		(pad "2" smd circle
			(at 0.40005 0 180)
			(size 0 0)
			(layers "F.Cu" "F.Mask" "F.Paste")
			(net "HP_LVC3_OCP_V3_1_ATTN_OUT_SW_N")
		)
	)
	(footprint ""
		(layer "F.Cu")
		(at 120.37822 -423.479468)
		(property "Reference" "R3508"
			(at 0 0 0)
			(layer "F.SilkS")
			(hide yes)
			(effects
				(font
					(size 1.27 1.27)
				)
			)
		)
		(property "Value" ""
			(at 0 0 0)
			(layer "F.Fab")
			(effects
				(font
					(size 1.27 1.27)
				)
			)
		)
		(duplicate_pad_numbers_are_jumpers no)
		(fp_line
			(start -0.7874 -0.4064)
			(end 0.7874 -0.4064)
			(stroke
				(width 0.1524)
				(type default)
			)
			(layer "F.SilkS")
		)
		(fp_line
			(start -0.7874 0.4064)
			(end -0.7874 -0.4064)
			(stroke
				(width 0.1524)
				(type default)
			)
			(layer "F.SilkS")
		)
		(fp_line
			(start 0.7874 -0.4064)
			(end 0.7874 0.4064)
			(stroke
				(width 0.1524)
				(type default)
			)
			(layer "F.SilkS")
		)
		(fp_line
			(start 0.7874 0.4064)
			(end -0.7874 0.4064)
			(stroke
				(width 0.1524)
				(type default)
			)
			(layer "F.SilkS")
		)
		(fp_line
			(start -0.67945 -0.305054)
			(end -0.12065 -0.305054)
			(stroke
				(width 0.1)
				(type default)
			)
			(layer "F.Fab")
		)
		(fp_line
			(start -0.67945 0.3048)
			(end -0.67945 -0.305054)
			(stroke
				(width 0.1)
				(type default)
			)
			(layer "F.Fab")
		)
		(fp_line
			(start -0.12065 -0.305054)
			(end -0.12065 -0.2794)
			(stroke
				(width 0.1)
				(type default)
			)
			(layer "F.Fab")
		)
		(fp_line
			(start -0.12065 -0.2794)
			(end 0.12065 -0.2794)
			(stroke
				(width 0.1)
				(type default)
			)
			(layer "F.Fab")
		)
		(fp_line
			(start -0.12065 0.2794)
			(end -0.12065 0.3048)
			(stroke
				(width 0.1)
				(type default)
			)
			(layer "F.Fab")
		)
		(fp_line
			(start -0.12065 0.3048)
			(end -0.67945 0.3048)
			(stroke
				(width 0.1)
				(type default)
			)
			(layer "F.Fab")
		)
		(fp_line
			(start 0.120396 0.2794)
			(end -0.12065 0.2794)
			(stroke
				(width 0.1)
				(type default)
			)
			(layer "F.Fab")
		)
		(fp_line
			(start 0.120396 0.3048)
			(end 0.120396 0.2794)
			(stroke
				(width 0.1)
				(type default)
			)
			(layer "F.Fab")
		)
		(fp_line
			(start 0.12065 -0.3048)
			(end 0.67945 -0.3048)
			(stroke
				(width 0.1)
				(type default)
			)
			(layer "F.Fab")
		)
		(fp_line
			(start 0.12065 -0.2794)
			(end 0.12065 -0.3048)
			(stroke
				(width 0.1)
				(type default)
			)
			(layer "F.Fab")
		)
		(fp_line
			(start 0.67945 -0.3048)
			(end 0.67945 0.3048)
			(stroke
				(width 0.1)
				(type default)
			)
			(layer "F.Fab")
		)
		(fp_line
			(start 0.67945 0.3048)
			(end 0.120396 0.3048)
			(stroke
				(width 0.1)
				(type default)
			)
			(layer "F.Fab")
		)
		(pad "1" smd circle
			(at -0.40005 0)
			(size 0 0)
			(layers "F.Cu" "F.Mask" "F.Paste")
			(net "FM_GPU_PWR_EN_R1")
		)
		(pad "2" smd circle
			(at 0.40005 0)
			(size 0 0)
			(layers "F.Cu" "F.Mask" "F.Paste")
			(net "GND")
		)
	)
	(footprint ""
		(layer "F.Cu")
		(at 459.280768 -398.59077)
		(property "Reference" "H27"
			(at -5.8166 -5.552948 0)
			(unlocked yes)
			(layer "F.SilkS")
			(effects
				(font
					(size 0.7874 0.5842)
					(thickness 0.1524)
				)
				(justify left)
			)
		)
		(property "Value" ""
			(at 0 0 0)
			(layer "F.Fab")
			(effects
				(font
					(size 1.27 1.27)
				)
			)
		)
		(duplicate_pad_numbers_are_jumpers no)
		(fp_circle
			(center 0 0)
			(end 2.4003 0)
			(stroke
				(width 0.1524)
				(type default)
			)
			(fill no)
			(layer "F.SilkS")
		)
		(fp_arc
			(start 5.688076 3.330194)
			(mid -6.590791 -0.091812)
			(end 5.7785 -3.170936)
			(stroke
				(width 0.1524)
				(type default)
			)
			(layer "B.SilkS")
		)
		(fp_circle
			(center 0 0)
			(end 6.5913 0)
			(stroke
				(width 0.1)
				(type default)
			)
			(fill no)
			(layer "B.Fab")
		)
		(fp_circle
			(center 0 0)
			(end 2.4003 0)
			(stroke
				(width 0.1)
				(type default)
			)
			(fill no)
			(layer "F.Fab")
		)
		(pad "" np_thru_hole circle
			(at 0 0)
			(size 3.175 3.175)
			(drill 3.175)
			(layers "*.Cu" "*.Mask")
			(clearance 0.381)
			(thermal_gap 0.381)
		)
		(zone
			(layers "F.Cu" "B.Cu" "In1.Cu" "In2.Cu" "In3.Cu" "In4.Cu" "In5.Cu" "In6.Cu"
				"In7.Cu" "In8.Cu" "In9.Cu" "In10.Cu" "In11.Cu" "In12.Cu" "In13.Cu" "In14.Cu"
				"In15.Cu" "In16.Cu"
			)
			(hatch none 0.5)
			(connect_pads
				(clearance 0)
			)
			(min_thickness 0.25)
			(keepout
				(tracks not_allowed)
				(vias allowed)
				(pads allowed)
				(copperpour not_allowed)
				(footprints allowed)
			)
			(placement
				(enabled no)
				(sheetname "")
			)
			(fill
				(thermal_gap 0.5)
				(thermal_bridge_width 0.5)
				(island_removal_mode 0)
			)
			(polygon
				(pts
					(arc
						(start 461.376268 -398.59077)
						(mid 457.185268 -398.59077)
						(end 461.376268 -398.59077)
					)
				)
			)
		)
	)
)
